(kicad_pcb
	(version 20260206)
	(generator "pcbnew")
	(generator_version "10.0")
	(general
		(thickness 1.6)
		(legacy_teardrops no)
	)
	(paper "A4")
	(title_block
		(title "Bryce Canyon_R.DPB_16317-1_OCP.brd")
		(comment 1 "Bryce Canyon / footprints 917-923 of 2099")
	)
	(layers
		(0 "F.Cu" signal "TOP")
		(4 "In1.Cu" signal "L2GND")
		(6 "In2.Cu" signal "L3")
		(8 "In3.Cu" signal "L4VCC")
		(10 "In4.Cu" signal "L5VCC")
		(12 "In5.Cu" signal "L6")
		(14 "In6.Cu" signal "L7GND")
		(2 "B.Cu" signal "BOTTOM")
		(9 "F.Adhes" user "F.Adhesive")
		(11 "B.Adhes" user "B.Adhesive")
		(13 "F.Paste" user "Package Geometry/Pastemask Top")
		(15 "B.Paste" user "Package Geometry/Pastemask Bottom")
		(5 "F.SilkS" user "Ref Des/Silkscreen Top")
		(7 "B.SilkS" user "Ref Des/Silkscreen Bottom")
		(1 "F.Mask" user "Board Geometry/Soldermask Top")
		(3 "B.Mask" user "Board Geometry/Soldermask Bottom")
		(17 "Dwgs.User" user "User.Drawings")
		(19 "Cmts.User" user "User.Comments")
		(21 "Eco1.User" user "User.Eco1")
		(23 "Eco2.User" user "User.Eco2")
		(25 "Edge.Cuts" user "Board Geometry/Outline")
		(27 "Margin" user)
		(31 "F.CrtYd" user "Package Geometry/Place Bound Top")
		(29 "B.CrtYd" user "Package Geometry/Place Bound Bottom")
		(35 "F.Fab" user "Ref Des/Assembly Top")
		(33 "B.Fab" user "Ref Des/Assembly Bottom")
	)
	(footprint ""
		(layer "F.Cu")
		(at 95.608902 -133.75005 -90)
		(property "Reference" "VIA30"
			(at 0 0 270)
			(layer "F.SilkS")
			(hide yes)
			(effects
				(font
					(size 1.27 1.27)
				)
			)
		)
		(property "Value" "100OHM-8L-2D36MM-L16-GP"
			(at -3.4036 -0.4572 270)
			(unlocked yes)
			(layer "F.Fab")
			(hide yes)
			(effects
				(font
					(size 1.016 1.016)
					(thickness 0.1524)
				)
			)
		)
		(property "Device Type" "VIA-PCIE-4P-427097"
			(at -3.4036 -1.9812 270)
			(unlocked yes)
			(layer "F.Fab")
			(hide yes)
			(effects
				(font
					(size 1.016 1.016)
					(thickness 0.1524)
				)
			)
		)
		(duplicate_pad_numbers_are_jumpers no)
		(fp_rect
			(start -2.1336 0.4826)
			(end 2.1336 -0.4826)
			(stroke
				(width 0)
				(type default)
			)
			(fill no)
			(layer "F.CrtYd")
		)
		(fp_rect
			(start -2.1336 0.4826)
			(end 2.1336 -0.4826)
			(stroke
				(width 0)
				(type default)
			)
			(fill no)
			(layer "F.Fab")
		)
		(pad "1" thru_hole circle
			(at -1.651 0 270)
			(size 0.508 0.508)
			(drill 0.254)
			(layers "*.Cu" "*.Mask")
			(remove_unused_layers no)
			(net "GND")
			(clearance 0.2286)
			(thermal_gap 0.2286)
		)
		(pad "2" thru_hole circle
			(at -0.635 0 270)
			(size 0.508 0.508)
			(drill 0.254)
			(layers "*.Cu" "*.Mask")
			(remove_unused_layers no)
			(net "PHY_DRV_B_TO_SCC_B_14_DP")
			(clearance 0.2286)
			(thermal_gap 0.2286)
		)
		(pad "3" thru_hole circle
			(at 0.635 0 270)
			(size 0.508 0.508)
			(drill 0.254)
			(layers "*.Cu" "*.Mask")
			(remove_unused_layers no)
			(net "PHY_DRV_B_TO_SCC_B_14_DN")
			(clearance 0.2286)
			(thermal_gap 0.2286)
		)
		(pad "4" thru_hole circle
			(at 1.651 0 270)
			(size 0.508 0.508)
			(drill 0.254)
			(layers "*.Cu" "*.Mask")
			(remove_unused_layers no)
			(net "GND")
			(clearance 0.2286)
			(thermal_gap 0.2286)
		)
	)
	(footprint ""
		(layer "F.Cu")
		(at 109.474 -145.796)
		(property "Reference" "Q66"
			(at 0 0 0)
			(layer "F.SilkS")
			(hide yes)
			(effects
				(font
					(size 1.27 1.27)
				)
			)
		)
		(property "Value" "AO4407AL-GP"
			(at -3.707384 -1.5367 0)
			(unlocked yes)
			(layer "F.Fab")
			(hide yes)
			(effects
				(font
					(size 1.016 1.016)
					(thickness 0.1524)
				)
			)
		)
		(property "Device Type" "SOIC8H69"
			(at -3.707384 -3.0607 0)
			(unlocked yes)
			(layer "F.Fab")
			(hide yes)
			(effects
				(font
					(size 1.016 1.016)
					(thickness 0.1524)
				)
			)
		)
		(duplicate_pad_numbers_are_jumpers no)
		(fp_line
			(start -2.7432 -1.4224)
			(end -2.7432 1.4224)
			(stroke
				(width 0.1524)
				(type default)
			)
			(layer "F.SilkS")
		)
		(fp_line
			(start -2.7432 1.4224)
			(end -2.6416 1.4224)
			(stroke
				(width 0.1524)
				(type default)
			)
			(layer "F.SilkS")
		)
		(fp_line
			(start -2.7432 1.4224)
			(end 2.1336 1.4224)
			(stroke
				(width 0.1524)
				(type default)
			)
			(layer "F.SilkS")
		)
		(fp_line
			(start -2.7178 -0.508)
			(end -2.1844 -0.0508)
			(stroke
				(width 0.1524)
				(type default)
			)
			(layer "F.SilkS")
		)
		(fp_line
			(start -2.6289 3.4417)
			(end -2.6289 1.4732)
			(stroke
				(width 0.381)
				(type default)
			)
			(layer "F.SilkS")
		)
		(fp_line
			(start -2.1844 -0.0508)
			(end -2.7178 0.508)
			(stroke
				(width 0.1524)
				(type default)
			)
			(layer "F.SilkS")
		)
		(fp_line
			(start 2.1336 -1.4224)
			(end -2.7432 -1.4224)
			(stroke
				(width 0.1524)
				(type default)
			)
			(layer "F.SilkS")
		)
		(fp_line
			(start 2.1336 1.4224)
			(end 2.1336 -1.4224)
			(stroke
				(width 0.1524)
				(type default)
			)
			(layer "F.SilkS")
		)
		(fp_poly
			(pts
				(xy -2.2098 -1.4224) (xy -2.2098 1.4224) (xy 2.2098 1.4224) (xy 2.2098 -1.4224)
			)
			(stroke
				(width 0)
				(type default)
			)
			(fill yes)
			(layer "F.SilkS")
		)
		(fp_rect
			(start -2.450084 2.999994)
			(end 2.450084 -2.999994)
			(stroke
				(width 0)
				(type default)
			)
			(fill no)
			(layer "F.CrtYd")
		)
		(fp_poly
			(pts
				(xy -2.8194 3.6322) (xy -2.8194 -3.6322) (xy 2.8194 -3.6322) (xy 2.8194 1.18364) (xy 2.450084 1.18364)
				(xy 2.450084 -2.999994) (xy -2.450084 -2.999994) (xy -2.450084 2.999994) (xy 2.450084 2.999994)
				(xy 2.450084 1.18618) (xy 2.8194 1.18618) (xy 2.8194 3.6322)
			)
			(stroke
				(width 0)
				(type default)
			)
			(fill no)
			(layer "F.CrtYd")
		)
		(fp_rect
			(start -2.8194 3.6322)
			(end 2.8194 -3.6322)
			(stroke
				(width 0)
				(type default)
			)
			(fill no)
			(layer "F.Fab")
		)
		(pad "1" smd rect
			(at -1.905 2.54)
			(size 0.635 1.651)
			(layers "F.Cu" "F.Mask" "F.Paste")
			(net "P12V_B")
		)
		(pad "2" smd rect
			(at -0.635 2.54)
			(size 0.635 1.651)
			(layers "F.Cu" "F.Mask" "F.Paste")
			(net "P12V_B")
		)
		(pad "3" smd rect
			(at 0.635 2.54)
			(size 0.635 1.651)
			(layers "F.Cu" "F.Mask" "F.Paste")
			(net "P12V_B")
		)
		(pad "4" smd rect
			(at 1.905 2.54)
			(size 0.635 1.651)
			(layers "F.Cu" "F.Mask" "F.Paste")
			(net "SW_HDD_N15")
		)
		(pad "5" smd rect
			(at 1.905 -2.54)
			(size 0.635 1.651)
			(layers "F.Cu" "F.Mask" "F.Paste")
			(net "P12V_HDD15")
		)
		(pad "6" smd rect
			(at 0.635 -2.54)
			(size 0.635 1.651)
			(layers "F.Cu" "F.Mask" "F.Paste")
			(net "P12V_HDD15")
		)
		(pad "7" smd rect
			(at -0.635 -2.54)
			(size 0.635 1.651)
			(layers "F.Cu" "F.Mask" "F.Paste")
			(net "P12V_HDD15")
		)
		(pad "8" smd rect
			(at -1.905 -2.54)
			(size 0.635 1.651)
			(layers "F.Cu" "F.Mask" "F.Paste")
			(net "P12V_HDD15")
		)
	)
	(footprint ""
		(layer "F.Cu")
		(at 18.415 -131.572)
		(property "Reference" "R363"
			(at 0 0 0)
			(layer "F.SilkS")
			(hide yes)
			(effects
				(font
					(size 1.27 1.27)
				)
			)
		)
		(property "Value" "0R2J-2-GP"
			(at 0.064008 -3.993896 0)
			(unlocked yes)
			(layer "F.Fab")
			(hide yes)
			(effects
				(font
					(size 1.016 1.016)
					(thickness 0.1524)
				)
			)
		)
		(property "Device Type" "R402H16"
			(at 0.064008 -5.517896 0)
			(unlocked yes)
			(layer "F.Fab")
			(hide yes)
			(effects
				(font
					(size 1.016 1.016)
					(thickness 0.1524)
				)
			)
		)
		(duplicate_pad_numbers_are_jumpers no)
		(fp_line
			(start -0.508 -0.9398)
			(end -0.508 0.9398)
			(stroke
				(width 0.1524)
				(type default)
			)
			(layer "F.SilkS")
		)
		(fp_line
			(start 0.508 -0.9398)
			(end -0.508 -0.9398)
			(stroke
				(width 0.1524)
				(type default)
			)
			(layer "F.SilkS")
		)
		(fp_rect
			(start -0.508 0.9398)
			(end 0.508 -0.9398)
			(stroke
				(width 0)
				(type default)
			)
			(fill no)
			(layer "F.CrtYd")
		)
		(fp_rect
			(start -0.508 0.9398)
			(end 0.508 -0.9398)
			(stroke
				(width 0)
				(type default)
			)
			(fill no)
			(layer "F.Fab")
		)
		(pad "1" smd custom
			(at 0 -0.4445)
			(size 0.1397 0.1397)
			(layers "F.Cu" "F.Mask" "F.Paste")
			(net "SW_HDD_G12")
			(options
				(clearance outline)
				(anchor circle)
			)
			(primitives
				(gr_poly
					(pts
						(arc
							(start -0.1778 -0.2794)
							(mid -0.249642 -0.249642)
							(end -0.2794 -0.1778)
						)
						(arc
							(start -0.2794 0.1778)
							(mid -0.249642 0.249642)
							(end -0.1778 0.2794)
						)
						(arc
							(start 0.1778 0.2794)
							(mid 0.249642 0.249642)
							(end 0.2794 0.1778)
						)
						(arc
							(start 0.2794 -0.1778)
							(mid 0.249642 -0.249642)
							(end 0.1778 -0.2794)
						)
					)
					(width 0)
					(fill yes)
				)
			)
		)
		(pad "2" smd custom
			(at 0 0.4445)
			(size 0.1397 0.1397)
			(layers "F.Cu" "F.Mask" "F.Paste")
			(net "SW_HDD_R12")
			(options
				(clearance outline)
				(anchor circle)
			)
			(primitives
				(gr_poly
					(pts
						(arc
							(start -0.1778 -0.2794)
							(mid -0.249642 -0.249642)
							(end -0.2794 -0.1778)
						)
						(arc
							(start -0.2794 0.1778)
							(mid -0.249642 0.249642)
							(end -0.1778 0.2794)
						)
						(arc
							(start 0.1778 0.2794)
							(mid 0.249642 0.249642)
							(end 0.2794 0.1778)
						)
						(arc
							(start 0.2794 -0.1778)
							(mid 0.249642 -0.249642)
							(end 0.1778 -0.2794)
						)
					)
					(width 0)
					(fill yes)
				)
			)
		)
	)
	(footprint ""
		(layer "F.Cu")
		(at 331.47 -160.02 180)
		(property "Reference" "C268"
			(at 0 0 180)
			(layer "F.SilkS")
			(hide yes)
			(effects
				(font
					(size 1.27 1.27)
				)
			)
		)
		(property "Value" "SC4D7U25V5KX-1-GP"
			(at -0.0762 -6.1214 180)
			(unlocked yes)
			(layer "F.Fab")
			(hide yes)
			(effects
				(font
					(size 1.016 1.016)
					(thickness 0.1524)
				)
			)
		)
		(property "Device Type" "C805H58"
			(at -0.0762 -8.1534 180)
			(unlocked yes)
			(layer "F.Fab")
			(hide yes)
			(effects
				(font
					(size 1.016 1.016)
					(thickness 0.1524)
				)
			)
		)
		(duplicate_pad_numbers_are_jumpers no)
		(fp_line
			(start 0.635 0)
			(end -0.635 0)
			(stroke
				(width 0.508)
				(type default)
			)
			(layer "F.SilkS")
		)
		(fp_rect
			(start -0.9652 1.778)
			(end 0.9652 -1.778)
			(stroke
				(width 0)
				(type default)
			)
			(fill no)
			(layer "F.CrtYd")
		)
		(fp_poly
			(pts
				(xy -0.9652 -1.778) (xy 0.9652 -1.778) (xy 0.9652 1.778) (xy -0.9652 1.778)
			)
			(stroke
				(width 0)
				(type default)
			)
			(fill no)
			(layer "F.Fab")
		)
		(pad "1" smd rect
			(at 0 -0.9652 180)
			(size 1.397 1.143)
			(layers "F.Cu" "F.Mask" "F.Paste")
			(net "P12V_HDD18")
		)
		(pad "2" smd rect
			(at 0 0.9652 180)
			(size 1.397 1.143)
			(layers "F.Cu" "F.Mask" "F.Paste")
			(net "GND")
		)
	)
	(footprint ""
		(layer "F.Cu")
		(at 243.519452 -362.284772)
		(property "Reference" "C565"
			(at 0 0 0)
			(layer "F.SilkS")
			(hide yes)
			(effects
				(font
					(size 1.27 1.27)
				)
			)
		)
		(property "Value" "SC1U16V3KX-5GP"
			(at 0 -2.8194 0)
			(unlocked yes)
			(layer "F.Fab")
			(hide yes)
			(effects
				(font
					(size 1.016 1.016)
					(thickness 0.1524)
				)
			)
		)
		(property "Device Type" "C603H36"
			(at 0 -4.3434 0)
			(unlocked yes)
			(layer "F.Fab")
			(hide yes)
			(effects
				(font
					(size 1.016 1.016)
					(thickness 0.1524)
				)
			)
		)
		(duplicate_pad_numbers_are_jumpers no)
		(fp_line
			(start 0.508 0)
			(end -0.508 0)
			(stroke
				(width 0.2032)
				(type default)
			)
			(layer "F.SilkS")
		)
		(fp_rect
			(start -0.5842 1.3335)
			(end 0.5842 -1.3335)
			(stroke
				(width 0)
				(type default)
			)
			(fill no)
			(layer "F.CrtYd")
		)
		(fp_rect
			(start -0.5842 1.3335)
			(end 0.5842 -1.3335)
			(stroke
				(width 0)
				(type default)
			)
			(fill no)
			(layer "F.Fab")
		)
		(pad "1" smd custom
			(at 0 -0.762)
			(size 0.2159 0.2159)
			(layers "F.Cu" "F.Mask" "F.Paste")
			(net "MB3_CM_UV_R")
			(options
				(clearance outline)
				(anchor circle)
			)
			(primitives
				(gr_poly
					(pts
						(arc
							(start -0.3302 -0.4318)
							(mid -0.402042 -0.402042)
							(end -0.4318 -0.3302)
						)
						(arc
							(start -0.4318 0.3302)
							(mid -0.402042 0.402042)
							(end -0.3302 0.4318)
						)
						(arc
							(start 0.3302 0.4318)
							(mid 0.402042 0.402042)
							(end 0.4318 0.3302)
						)
						(arc
							(start 0.4318 -0.3302)
							(mid 0.402042 -0.402042)
							(end 0.3302 -0.4318)
						)
					)
					(width 0)
					(fill yes)
				)
			)
		)
		(pad "2" smd custom
			(at 0 0.762)
			(size 0.2159 0.2159)
			(layers "F.Cu" "F.Mask" "F.Paste")
			(net "AGND_CURRENT_DPB")
			(options
				(clearance outline)
				(anchor circle)
			)
			(primitives
				(gr_poly
					(pts
						(arc
							(start -0.3302 -0.4318)
							(mid -0.402042 -0.402042)
							(end -0.4318 -0.3302)
						)
						(arc
							(start -0.4318 0.3302)
							(mid -0.402042 0.402042)
							(end -0.3302 0.4318)
						)
						(arc
							(start 0.3302 0.4318)
							(mid 0.402042 0.402042)
							(end 0.4318 0.3302)
						)
						(arc
							(start 0.4318 -0.3302)
							(mid 0.402042 -0.402042)
							(end 0.3302 -0.4318)
						)
					)
					(width 0)
					(fill yes)
				)
			)
		)
	)
	(footprint ""
		(layer "F.Cu")
		(at 426.085 -274.955 180)
		(property "Reference" "C151"
			(at 0 0 180)
			(layer "F.SilkS")
			(hide yes)
			(effects
				(font
					(size 1.27 1.27)
				)
			)
		)
		(property "Value" "SC4D7U25V5KX-1-GP"
			(at -0.0762 -6.1214 180)
			(unlocked yes)
			(layer "F.Fab")
			(hide yes)
			(effects
				(font
					(size 1.016 1.016)
					(thickness 0.1524)
				)
			)
		)
		(property "Device Type" "C805H58"
			(at -0.0762 -8.1534 180)
			(unlocked yes)
			(layer "F.Fab")
			(hide yes)
			(effects
				(font
					(size 1.016 1.016)
					(thickness 0.1524)
				)
			)
		)
		(duplicate_pad_numbers_are_jumpers no)
		(fp_line
			(start 0.635 0)
			(end -0.635 0)
			(stroke
				(width 0.508)
				(type default)
			)
			(layer "F.SilkS")
		)
		(fp_rect
			(start -0.9652 1.778)
			(end 0.9652 -1.778)
			(stroke
				(width 0)
				(type default)
			)
			(fill no)
			(layer "F.CrtYd")
		)
		(fp_poly
			(pts
				(xy -0.9652 -1.778) (xy 0.9652 -1.778) (xy 0.9652 1.778) (xy -0.9652 1.778)
			)
			(stroke
				(width 0)
				(type default)
			)
			(fill no)
			(layer "F.Fab")
		)
		(pad "1" smd rect
			(at 0 -0.9652 180)
			(size 1.397 1.143)
			(layers "F.Cu" "F.Mask" "F.Paste")
			(net "P12V_HDD9")
		)
		(pad "2" smd rect
			(at 0 0.9652 180)
			(size 1.397 1.143)
			(layers "F.Cu" "F.Mask" "F.Paste")
			(net "GND")
		)
	)
	(footprint ""
		(layer "F.Cu")
		(at 402.843746 -99.860354 90)
		(property "Reference" "Q262"
			(at 0 0 90)
			(layer "F.SilkS")
			(hide yes)
			(effects
				(font
					(size 1.27 1.27)
				)
			)
		)
		(property "Value" "SSM3K324R-GP"
			(at 0.127 -8.9662 90)
			(unlocked yes)
			(layer "F.Fab")
			(hide yes)
			(effects
				(font
					(size 1.016 1.016)
					(thickness 0.1524)
				)
			)
		)
		(property "Device Type" "SOT23DGS2D4H35"
			(at 0.127 -10.4902 90)
			(unlocked yes)
			(layer "F.Fab")
			(hide yes)
			(effects
				(font
					(size 1.016 1.016)
					(thickness 0.1524)
				)
			)
		)
		(duplicate_pad_numbers_are_jumpers no)
		(fp_line
			(start 1.651 -1.778)
			(end -1.651 -1.778)
			(stroke
				(width 0.1524)
				(type default)
			)
			(layer "F.SilkS")
		)
		(fp_line
			(start -1.651 -1.778)
			(end -1.651 1.778)
			(stroke
				(width 0.1524)
				(type default)
			)
			(layer "F.SilkS")
		)
		(fp_line
			(start 1.651 1.778)
			(end 1.651 -1.778)
			(stroke
				(width 0.1524)
				(type default)
			)
			(layer "F.SilkS")
		)
		(fp_line
			(start -1.651 1.778)
			(end 1.651 1.778)
			(stroke
				(width 0.1524)
				(type default)
			)
			(layer "F.SilkS")
		)
		(fp_poly
			(pts
				(xy -1.778 1.8796) (xy -1.778 -1.8796) (xy 1.778 -1.8796) (xy 1.778 1.8796)
			)
			(stroke
				(width 0)
				(type default)
			)
			(fill no)
			(layer "F.CrtYd")
		)
		(fp_poly
			(pts
				(xy -1.778 1.8796) (xy -1.778 -1.8796) (xy 1.778 -1.8796) (xy 1.778 1.8796)
			)
			(stroke
				(width 0)
				(type default)
			)
			(fill no)
			(layer "F.Fab")
		)
		(pad "D" smd custom
			(at 0 -0.9525 90)
			(size 0.1905 0.1905)
			(layers "F.Cu" "F.Mask" "F.Paste")
			(net "DRV_ACT_21_N")
			(options
				(clearance outline)
				(anchor circle)
			)
			(primitives
				(gr_poly
					(pts
						(arc
							(start -0.1778 0.5715)
							(mid -0.321484 0.511984)
							(end -0.381 0.3683)
						)
						(arc
							(start -0.381 -0.3683)
							(mid -0.321484 -0.511984)
							(end -0.1778 -0.5715)
						)
						(arc
							(start 0.1778 -0.5715)
							(mid 0.321484 -0.511984)
							(end 0.381 -0.3683)
						)
						(arc
							(start 0.381 0.3683)
							(mid 0.321484 0.511984)
							(end 0.1778 0.5715)
						)
					)
					(width 0)
					(fill yes)
				)
			)
		)
		(pad "G" smd custom
			(at -0.98425 0.9525 90)
			(size 0.1905 0.1905)
			(layers "F.Cu" "F.Mask" "F.Paste")
			(net "DRIVE_B_21_ACT")
			(options
				(clearance outline)
				(anchor circle)
			)
			(primitives
				(gr_poly
					(pts
						(arc
							(start -0.1778 0.5715)
							(mid -0.321484 0.511984)
							(end -0.381 0.3683)
						)
						(arc
							(start -0.381 -0.3683)
							(mid -0.321484 -0.511984)
							(end -0.1778 -0.5715)
						)
						(arc
							(start 0.1778 -0.5715)
							(mid 0.321484 -0.511984)
							(end 0.381 -0.3683)
						)
						(arc
							(start 0.381 0.3683)
							(mid 0.321484 0.511984)
							(end 0.1778 0.5715)
						)
					)
					(width 0)
					(fill yes)
				)
			)
		)
		(pad "S" smd custom
			(at 0.98425 0.9525 90)
			(size 0.1905 0.1905)
			(layers "F.Cu" "F.Mask" "F.Paste")
			(net "GND")
			(options
				(clearance outline)
				(anchor circle)
			)
			(primitives
				(gr_poly
					(pts
						(arc
							(start -0.1778 0.5715)
							(mid -0.321484 0.511984)
							(end -0.381 0.3683)
						)
						(arc
							(start -0.381 -0.3683)
							(mid -0.321484 -0.511984)
							(end -0.1778 -0.5715)
						)
						(arc
							(start 0.1778 -0.5715)
							(mid 0.321484 -0.511984)
							(end 0.381 -0.3683)
						)
						(arc
							(start 0.381 0.3683)
							(mid 0.321484 0.511984)
							(end 0.1778 0.5715)
						)
					)
					(width 0)
					(fill yes)
				)
			)
		)
	)
)
